# S9S_MB_2U (Grand Teton) — schematic parts with pin connectivity, parts 1618–1618 of 6093; source: Cadence DE-HDL packaged netlist (pstxprt.dat, pstxnet.dat, pstchip.dat)

J25  SCONN288_ADR50017P130CC  SCONN288_ADR50017-P130CC IO  pkg DDR288S_1-1VXB  page 106
  1  VIN_BULK0  POWER  = P12V_S3_AUX_CPU1_NVDIMM
  2  RFU0  TRI  = TP_CHE_CPU1_DIMM1_FRU_0
  3  VIN_MGMT  POWER  = P3V3_AUX
  4  HSCL  IN  = I3C_SPD_DDREFGH_CPU1_LVC1_SCL_R
  5  HSDA  BI  = I3C_SPD_DDREFGH_CPU1_LVC1_SDA
  6  VSS0  POWER  = GND
  7  DQ0_A  BI  = M_E_CPU1_SA_DQ<0>
  8  VSS1  POWER  = GND
  9  DQ1_A  BI  = M_E_CPU1_SA_DQ<1>
  10  VSS2  POWER  = GND
  11  DQS0_A_T  BI  = M_E_CPU1_SA_DQS_DP<0>
  12  DQS0_A_C  BI  = M_E_CPU1_SA_DQS_DN<0>
  13  VSS3  POWER  = GND
  14  DQ4_A  BI  = M_E_CPU1_SA_DQ<4>
  15  VSS4  POWER  = GND
  16  DQ5_A  BI  = M_E_CPU1_SA_DQ<5>
  17  VSS5  POWER  = GND
  18  DQ8_A  BI  = M_E_CPU1_SA_DQ<8>
  19  VSS6  POWER  = GND
  20  DQ9_A  BI  = M_E_CPU1_SA_DQ<9>
  21  VSS7  POWER  = GND
  22  DQS1_A_T  BI  = M_E_CPU1_SA_DQS_DP<1>
  23  DQS1_A_C  BI  = M_E_CPU1_SA_DQS_DN<1>
  24  VSS8  POWER  = GND
  25  DQ12_A  BI  = M_E_CPU1_SA_DQ<12>
  26  VSS9  POWER  = GND
  27  DQ13_A  BI  = M_E_CPU1_SA_DQ<13>
  28  VSS10  POWER  = GND
  29  DQ16_A  BI  = M_E_CPU1_SA_DQ<16>
  30  VSS11  POWER  = GND
  31  DQ17_A  BI  = M_E_CPU1_SA_DQ<17>
  32  VSS12  POWER  = GND
  33  DQS2_A_T  BI  = M_E_CPU1_SA_DQS_DP<2>
  34  DQS2_A_C  BI  = M_E_CPU1_SA_DQS_DN<2>
  35  VSS13  POWER  = GND
  36  DQ20_A  BI  = M_E_CPU1_SA_DQ<20>
  37  VSS14  POWER  = GND
  38  DQ21_A  BI  = M_E_CPU1_SA_DQ<21>
  39  VSS15  POWER  = GND
  40  DQ24_A  BI  = M_E_CPU1_SA_DQ<24>
  41  VSS16  POWER  = GND
  42  DQ25_A  BI  = M_E_CPU1_SA_DQ<25>
  43  VSS17  POWER  = GND
  44  DQS3_A_T  BI  = M_E_CPU1_SA_DQS_DP<3>
  45  DQS3_A_C  BI  = M_E_CPU1_SA_DQS_DN<3>
  46  VSS18  POWER  = GND
  47  DQ28_A  BI  = M_E_CPU1_SA_DQ<28>
  48  VSS19  POWER  = GND
  49  DQ29_A  BI  = M_E_CPU1_SA_DQ<29>
  50  VSS20  POWER  = GND
  51  CB0_A  BI  = M_E_CPU1_SA_CB<0>
  52  VSS21  POWER  = GND
  53  CB1_A  BI  = M_E_CPU1_SA_CB<1>
  54  VSS22  POWER  = GND
  55  DQS4_A_T  BI  = M_E_CPU1_SA_DQS_DP<4>
  56  DQS4_A_C  BI  = M_E_CPU1_SA_DQS_DN<4>
  57  VSS23  POWER  = GND
  58  CB4_A  BI  = M_E_CPU1_SA_CB<4>
  59  VSS24  POWER  = GND
  60  CB5_A  BI  = M_E_CPU1_SA_CB<5>
  61  VSS25  POWER  = GND
  62  ALERT_N  OUT  = M_E_CPU1_ALERT_N
  63  VSS26  POWER  = GND
  64  CS0_A_N  IN  = M_E_CPU1_SA_CS_N<0>
  65  VSS27  POWER  = GND
  66  CA0_A  IN  = M_E_CPU1_SA_CA<0>
  67  VSS28  POWER  = GND
  68  CA2_A  IN  = M_E_CPU1_SA_CA<2>
  69  VSS29  POWER  = GND
  70  CA4_A  IN  = M_E_CPU1_SA_CA<4>
  71  VSS30  POWER  = GND
  72  CA6_A  IN  = M_E_CPU1_SA_CA<6>
  73  VSS31  POWER  = GND
  74  PAR_A  IN  = M_E_CPU1_SA_PAR
  75  VSS32  POWER  = GND
  76  CA0_B  IN  = M_E_CPU1_SB_CA<0>
  77  VSS33  POWER  = GND
  78  CA2_B  IN  = M_E_CPU1_SB_CA<2>
  79  VSS34  POWER  = GND
  80  CA4_B  IN  = M_E_CPU1_SB_CA<4>
  81  VSS35  POWER  = GND
  82  CA6_B  IN  = M_E_CPU1_SB_CA<6>
  83  VSS36  POWER  = GND
  84  CS0_B_N  IN  = M_E_CPU1_SB_CS_N<0>
  85  VSS37  POWER  = GND
  86  \lbd||rsp_a_n\  OUT  = M_E_CPU1_SA_RSP<0>
  87  \lbs||rsp_b_n\  OUT  = M_E_CPU1_SB_RSP<0>
  88  VSS38  POWER  = GND
  89  CB4_B  BI  = M_E_CPU1_SB_CB<4>
  90  VSS39  POWER  = GND
  91  CB5_B  BI  = M_E_CPU1_SB_CB<5>
  92  VSS40  POWER  = GND
  93  \dqs9_b_t||tdqs9_b_t||dbi4_b_n\  BI  = M_E_CPU1_SB_DQS_DP<9>
  94  \dqs9_b_c||tdqs9_b_c\  BI  = M_E_CPU1_SB_DQS_DN<9>
  95  VSS41  POWER  = GND
  96  CB0_B  BI  = M_E_CPU1_SB_CB<0>
  97  VSS42  POWER  = GND
  98  CB1_B  BI  = M_E_CPU1_SB_CB<1>
  99  VSS43  POWER  = GND
  100  DQ0_B  BI  = M_E_CPU1_SB_DQ<0>
  101  VSS44  POWER  = GND
  102  DQ1_B  BI  = M_E_CPU1_SB_DQ<1>
  103  VSS45  POWER  = GND
  104  DQS0_B_T  BI  = M_E_CPU1_SB_DQS_DP<0>
  105  DQS0_B_C  BI  = M_E_CPU1_SB_DQS_DN<0>
  106  VSS46  POWER  = GND
  107  DQ4_B  BI  = M_E_CPU1_SB_DQ<4>
  108  VSS47  POWER  = GND
  109  DQ5_B  BI  = M_E_CPU1_SB_DQ<5>
  110  VSS48  POWER  = GND
  111  DQ8_B  BI  = M_E_CPU1_SB_DQ<8>
  112  VSS49  POWER  = GND
  113  DQ9_B  BI  = M_E_CPU1_SB_DQ<9>
  114  VSS50  POWER  = GND
  115  DQS1_B_T  BI  = M_E_CPU1_SB_DQS_DP<1>
  116  DQS1_B_C  BI  = M_E_CPU1_SB_DQS_DN<1>
  117  VSS51  POWER  = GND
  118  DQ12_B  BI  = M_E_CPU1_SB_DQ<12>
  119  VSS52  POWER  = GND
  120  DQ13_B  BI  = M_E_CPU1_SB_DQ<13>
  121  VSS53  POWER  = GND
  122  DQ16_B  BI  = M_E_CPU1_SB_DQ<16>
  123  VSS54  POWER  = GND
  124  DQ17_B  BI  = M_E_CPU1_SB_DQ<17>
  125  VSS55  POWER  = GND
  126  DQS2_B_T  BI  = M_E_CPU1_SB_DQS_DP<2>
  127  DQS2_B_C  BI  = M_E_CPU1_SB_DQS_DN<2>
  128  VSS56  POWER  = GND
  129  DQ20_B  BI  = M_E_CPU1_SB_DQ<20>
  130  VSS57  POWER  = GND
  131  DQ21_B  BI  = M_E_CPU1_SB_DQ<21>
  132  VSS58  POWER  = GND
  133  DQ24_B  BI  = M_E_CPU1_SB_DQ<24>
  134  VSS59  POWER  = GND
  135  DQ25_B  BI  = M_E_CPU1_SB_DQ<25>
  136  VSS60  POWER  = GND
  137  DQS3_B_T  BI  = M_E_CPU1_SB_DQS_DP<3>
  138  DQS3_B_C  BI  = M_E_CPU1_SB_DQS_DN<3>
  139  VSS61  POWER  = GND
  140  DQ28_B  BI  = M_E_CPU1_SB_DQ<28>
  141  VSS62  POWER  = GND
  142  DQ29_B  BI  = M_E_CPU1_SB_DQ<29>
  143  VSS63  POWER  = GND
  144  RFU1  TRI  = TP_CHE_CPU1_DIMM1_FRU_1
  145  VIN_BULK1  POWER  = P12V_S3_AUX_CPU1_NVDIMM
  146  VIN_BULK2  POWER  = P12V_S3_AUX_CPU1_NVDIMM
  147  \pwr_good||fail_n\  BI  = PWRGD_CHE_CPU1_DIMM1
  148  HSA  IN  = PD_CHE_CPU1_DIMM1_SAA
  149  RFU2  TRI  = TP_CHE_CPU1_DIMM1_FRU_2
  150  RFU3  TRI  = TP_CHE_CPU1_DIMM1_FRU_3
  151  VSS64  POWER  = GND
  152  DQ2_A  BI  = M_E_CPU1_SA_DQ<2>
  153  VSS65  POWER  = GND
  154  DQ3_A  BI  = M_E_CPU1_SA_DQ<3>
  155  VSS66  POWER  = GND
  156  \dqs5_a_c||tdqs5_a_c||dqs5_a_t||tdqs5_a_t\  BI  = M_E_CPU1_SA_DQS_DN<5>
  157  \dqs5_a_t||tdqs5_a_t\  BI  = M_E_CPU1_SA_DQS_DP<5>
  158  VSS67  POWER  = GND
  159  DQ6_A  BI  = M_E_CPU1_SA_DQ<6>
  160  VSS68  POWER  = GND
  161  DQ7_A  BI  = M_E_CPU1_SA_DQ<7>
  162  VSS69  POWER  = GND
  163  DQ10_A  BI  = M_E_CPU1_SA_DQ<10>
  164  VSS70  POWER  = GND
  165  DQ11_A  BI  = M_E_CPU1_SA_DQ<11>
  166  VSS71  POWER  = GND
  167  \dqs6_a_c||tdqs6_a_c||dqs6_a_t||tdqs6_a_t\  BI  = M_E_CPU1_SA_DQS_DN<6>
  168  \dqs6_a_t||tdqs6_a_t\  BI  = M_E_CPU1_SA_DQS_DP<6>
  169  VSS72  POWER  = GND
  170  DQ14_A  BI  = M_E_CPU1_SA_DQ<14>
  171  VSS73  POWER  = GND
  172  DQ15_A  BI  = M_E_CPU1_SA_DQ<15>
  173  VSS74  POWER  = GND
  174  DQ18_A  BI  = M_E_CPU1_SA_DQ<18>
  175  VSS75  POWER  = GND
  176  DQ19_A  BI  = M_E_CPU1_SA_DQ<19>
  177  VSS76  POWER  = GND
  178  \dqs7_a_c||tdqs7_a_c\  BI  = M_E_CPU1_SA_DQS_DN<7>
  179  \dqs7_a_t||tdqs7_a_t\  BI  = M_E_CPU1_SA_DQS_DP<7>
  180  VSS77  POWER  = GND
  181  DQ22_A  BI  = M_E_CPU1_SA_DQ<22>
  182  VSS78  POWER  = GND
  183  DQ23_A  BI  = M_E_CPU1_SA_DQ<23>
  184  VSS79  POWER  = GND
  185  DQ26_A  BI  = M_E_CPU1_SA_DQ<26>
  186  VSS80  POWER  = GND
  187  DQ27_A  BI  = M_E_CPU1_SA_DQ<27>
  188  VSS81  POWER  = GND
  189  \dqs8_a_c||tdqs8_a_c\  BI  = M_E_CPU1_SA_DQS_DN<8>
  190  \dqs8_a_t||tdqs8_a_t\  BI  = M_E_CPU1_SA_DQS_DP<8>
  191  VSS82  POWER  = GND
  192  DQ30_A  BI  = M_E_CPU1_SA_DQ<30>
  193  VSS83  POWER  = GND
  194  DQ31_A  BI  = M_E_CPU1_SA_DQ<31>
  195  VSS84  POWER  = GND
  196  CB2_A  BI  = M_E_CPU1_SA_CB<2>
  197  VSS85  POWER  = GND
  198  CB3_A  BI  = M_E_CPU1_SA_CB<3>
  199  VSS86  POWER  = GND
  200  \dqs9_a_c||tdqs9_a_c\  BI  = M_E_CPU1_SA_DQS_DN<9>
  201  \dqs9_a_t||tdqs9_a_t\  BI  = M_E_CPU1_SA_DQS_DP<9>
  202  VSS87  POWER  = GND
  203  CB6_A  BI  = M_E_CPU1_SA_CB<6>
  204  VSS88  POWER  = GND
  205  CB7_A  BI  = M_E_CPU1_SA_CB<7>
  206  VSS89  POWER  = GND
  207  RESET_N  IN  = RST_M_EF_CPU1_FPGA_N
  208  VSS90  POWER  = GND
  209  CS1_A_N  IN  = M_E_CPU1_SA_CS_N<1>
  210  VSS91  POWER  = GND
  211  CA1_A  IN  = M_E_CPU1_SA_CA<1>
  212  VSS92  POWER  = GND
  213  CA3_A  IN  = M_E_CPU1_SA_CA<3>
  214  VSS93  POWER  = GND
  215  CA5_A  IN  = M_E_CPU1_SA_CA<5>
  216  VSS94  POWER  = GND
  217  CK_T  IN  = M_E_CPU1_CLK_DP<0>
  218  CK_C  IN  = M_E_CPU1_CLK_DN<0>
  219  VSS95  POWER  = GND
  220  RFU4  TRI  = TP_CHE_CPU1_DIMM1_FRU_4
  221  CA1_B  IN  = M_E_CPU1_SB_CA<1>
  222  VSS96  POWER  = GND
  223  CA3_B  IN  = M_E_CPU1_SB_CA<3>
  224  VSS97  POWER  = GND
  225  CA5_B  IN  = M_E_CPU1_SB_CA<5>
  226  VSS98  POWER  = GND
  227  PAR_B  IN  = M_E_CPU1_SB_PAR
  228  VSS99  POWER  = GND
  229  CS1_B_N  IN  = M_E_CPU1_SB_CS_N<1>
  230  VSS100  POWER  = GND
  231  RFU5  TRI  = TP_CHE_CPU1_DIMM1_FRU_5
  232  RFU6  TRI  = TP_CHE_CPU1_DIMM1_FRU_6
  233  VSS101  POWER  = GND
  234  CB6_B  BI  = M_E_CPU1_SB_CB<6>
  235  VSS102  POWER  = GND
  236  CB7_B  BI  = M_E_CPU1_SB_CB<7>
  237  VSS103  POWER  = GND
  238  DQS4_B_C  BI  = M_E_CPU1_SB_DQS_DN<4>
  239  DQS4_B_T  BI  = M_E_CPU1_SB_DQS_DP<4>
  240  VSS104  POWER  = GND
  241  CB2_B  BI  = M_E_CPU1_SB_CB<2>
  242  VSS105  POWER  = GND
  243  CB3_B  BI  = M_E_CPU1_SB_CB<3>
  244  VSS106  POWER  = GND
  245  DQ2_B  BI  = M_E_CPU1_SB_DQ<2>
  246  VSS107  POWER  = GND
  247  DQ3_B  BI  = M_E_CPU1_SB_DQ<3>
  248  VSS108  POWER  = GND
  249  \dqs5_b_c||tdqs5_b_c\  BI  = M_E_CPU1_SB_DQS_DN<5>
  250  \dqs5_b_t||tdqs5_b_t\  BI  = M_E_CPU1_SB_DQS_DP<5>
  251  VSS109  POWER  = GND
  252  DQ6_B  BI  = M_E_CPU1_SB_DQ<6>
  253  VSS110  POWER  = GND
  254  DQ7_B  BI  = M_E_CPU1_SB_DQ<7>
  255  VSS111  POWER  = GND
  256  DQ10_B  BI  = M_E_CPU1_SB_DQ<10>
  257  VSS112  POWER  = GND
  258  DQ11_B  BI  = M_E_CPU1_SB_DQ<11>
  259  VSS113  POWER  = GND
  260  \dqs6_b_c||tdqs6_b_c\  BI  = M_E_CPU1_SB_DQS_DN<6>
  261  \dqs6_b_t||tdqs6_b_t\  BI  = M_E_CPU1_SB_DQS_DP<6>
  262  VSS114  POWER  = GND
  263  DQ14_B  BI  = M_E_CPU1_SB_DQ<14>
  264  VSS115  POWER  = GND
  265  DQ15_B  BI  = M_E_CPU1_SB_DQ<15>
  266  VSS116  POWER  = GND
  267  DQ18_B  BI  = M_E_CPU1_SB_DQ<18>
  268  VSS117  POWER  = GND
  269  DQ19_B  BI  = M_E_CPU1_SB_DQ<19>
  270  VSS118  POWER  = GND
  271  \dqs7_b_c||tdqs7_b_c\  BI  = M_E_CPU1_SB_DQS_DN<7>
  272  \dqs7_b_t||tdqs7_b_t\  BI  = M_E_CPU1_SB_DQS_DP<7>
  273  VSS119  POWER  = GND
  274  DQ22_B  BI  = M_E_CPU1_SB_DQ<22>
  275  VSS120  POWER  = GND
  276  DQ23_B  BI  = M_E_CPU1_SB_DQ<23>
  277  VSS121  POWER  = GND
  278  DQ26_B  BI  = M_E_CPU1_SB_DQ<26>
  279  VSS122  POWER  = GND
  280  DQ27_B  BI  = M_E_CPU1_SB_DQ<27>
  281  VSS123  POWER  = GND
  282  \dqs8_b_c||tdqs8_b_c\  BI  = M_E_CPU1_SB_DQS_DN<8>
  283  \dqs8_b_t||tdqs8_b_t\  BI  = M_E_CPU1_SB_DQS_DP<8>
  284  VSS124  POWER  = GND
  285  DQ30_B  BI  = M_E_CPU1_SB_DQ<30>
  286  VSS125  POWER  = GND
  287  DQ31_B  BI  = M_E_CPU1_SB_DQ<31>
  288  VSS126  POWER  = GND
  G1  G1  POWER  = GND
  G2  G2  POWER  = GND
  G3  G3  POWER  = GND
